(kicad_pcb
	(version 20260206)
	(generator "pcbnew")
	(generator_version "10.0")
	(general
		(thickness 1.6)
		(legacy_teardrops no)
	)
	(paper "A4")
	(title_block
		(title "12092022_DA0F0TMDCD0_F0T_Management_Board_D_brd_V3_OCP.brd")
		(comment 1 "Grand Teton / footprints 1416-1421 of 1440")
	)
	(layers
		(0 "F.Cu" signal "TOP")
		(4 "In1.Cu" signal "GND")
		(6 "In2.Cu" signal "IN1")
		(8 "In3.Cu" signal "GND1")
		(10 "In4.Cu" signal "IN2")
		(12 "In5.Cu" signal "VCC")
		(14 "In6.Cu" signal "VCC1")
		(16 "In7.Cu" signal "IN3")
		(18 "In8.Cu" signal "GND2")
		(20 "In9.Cu" signal "IN4")
		(22 "In10.Cu" signal "GND3")
		(2 "B.Cu" signal "BOTTOM")
		(9 "F.Adhes" user "F.Adhesive")
		(11 "B.Adhes" user "B.Adhesive")
		(13 "F.Paste" user "Package Geometry/Pastemask Top")
		(15 "B.Paste" user "Package Geometry/Pastemask Bottom")
		(5 "F.SilkS" user "Ref Des/Silkscreen Top")
		(7 "B.SilkS" user "Ref Des/Silkscreen Bottom")
		(1 "F.Mask" user "Board Geometry/Soldermask Top")
		(3 "B.Mask" user "Board Geometry/Soldermask Bottom")
		(17 "Dwgs.User" user "User.Drawings")
		(19 "Cmts.User" user "User.Comments")
		(21 "Eco1.User" user "User.Eco1")
		(23 "Eco2.User" user "User.Eco2")
		(25 "Edge.Cuts" user "Board Geometry/Outline")
		(27 "Margin" user)
		(31 "F.CrtYd" user "Package Geometry/Place Bound Top")
		(29 "B.CrtYd" user "Package Geometry/Place Bound Bottom")
		(35 "F.Fab" user "Ref Des/Assembly Top")
		(33 "B.Fab" user "Ref Des/Assembly Bottom")
	)
	(footprint ""
		(layer "B.Cu")
		(at 83.283552 -27.607768 180)
		(property "Reference" "R412"
			(at 0 0 0)
			(layer "B.SilkS")
			(hide yes)
			(effects
				(font
					(size 1.27 1.27)
				)
				(justify mirror)
			)
		)
		(property "Value" ""
			(at 0 0 0)
			(layer "B.Fab")
			(effects
				(font
					(size 1.27 1.27)
				)
				(justify mirror)
			)
		)
		(duplicate_pad_numbers_are_jumpers no)
		(fp_line
			(start 0.7874 0.4064)
			(end 0.7874 -0.4064)
			(stroke
				(width 0.1524)
				(type default)
			)
			(layer "B.SilkS")
		)
		(fp_line
			(start 0.7874 -0.4064)
			(end -0.7874 -0.4064)
			(stroke
				(width 0.1524)
				(type default)
			)
			(layer "B.SilkS")
		)
		(fp_line
			(start -0.7874 0.4064)
			(end 0.7874 0.4064)
			(stroke
				(width 0.1524)
				(type default)
			)
			(layer "B.SilkS")
		)
		(fp_line
			(start -0.7874 -0.4064)
			(end -0.7874 0.4064)
			(stroke
				(width 0.1524)
				(type default)
			)
			(layer "B.SilkS")
		)
		(fp_line
			(start 0.67945 0.3048)
			(end 0.67945 -0.305054)
			(stroke
				(width 0.1)
				(type default)
			)
			(layer "B.Fab")
		)
		(fp_line
			(start 0.67945 -0.305054)
			(end 0.12065 -0.305054)
			(stroke
				(width 0.1)
				(type default)
			)
			(layer "B.Fab")
		)
		(fp_line
			(start 0.12065 0.3048)
			(end 0.67945 0.3048)
			(stroke
				(width 0.1)
				(type default)
			)
			(layer "B.Fab")
		)
		(fp_line
			(start 0.12065 0.2794)
			(end 0.12065 0.3048)
			(stroke
				(width 0.1)
				(type default)
			)
			(layer "B.Fab")
		)
		(fp_line
			(start 0.12065 -0.2794)
			(end -0.12065 -0.2794)
			(stroke
				(width 0.1)
				(type default)
			)
			(layer "B.Fab")
		)
		(fp_line
			(start 0.12065 -0.305054)
			(end 0.12065 -0.2794)
			(stroke
				(width 0.1)
				(type default)
			)
			(layer "B.Fab")
		)
		(fp_line
			(start -0.120396 0.3048)
			(end -0.120396 0.2794)
			(stroke
				(width 0.1)
				(type default)
			)
			(layer "B.Fab")
		)
		(fp_line
			(start -0.120396 0.2794)
			(end 0.12065 0.2794)
			(stroke
				(width 0.1)
				(type default)
			)
			(layer "B.Fab")
		)
		(fp_line
			(start -0.12065 -0.2794)
			(end -0.12065 -0.3048)
			(stroke
				(width 0.1)
				(type default)
			)
			(layer "B.Fab")
		)
		(fp_line
			(start -0.12065 -0.3048)
			(end -0.67945 -0.3048)
			(stroke
				(width 0.1)
				(type default)
			)
			(layer "B.Fab")
		)
		(fp_line
			(start -0.67945 0.3048)
			(end -0.120396 0.3048)
			(stroke
				(width 0.1)
				(type default)
			)
			(layer "B.Fab")
		)
		(fp_line
			(start -0.67945 -0.3048)
			(end -0.67945 0.3048)
			(stroke
				(width 0.1)
				(type default)
			)
			(layer "B.Fab")
		)
		(pad "1" smd circle
			(at 0.40005 0)
			(size 0 0)
			(layers "B.Cu" "B.Mask" "B.Paste")
			(net "FRU_E1")
		)
		(pad "2" smd circle
			(at -0.40005 0)
			(size 0 0)
			(layers "B.Cu" "B.Mask" "B.Paste")
			(net "GND")
		)
	)
	(footprint ""
		(layer "B.Cu")
		(at 33.6296 -22.8346 -90)
		(property "Reference" "R28"
			(at 0 0 90)
			(layer "B.SilkS")
			(hide yes)
			(effects
				(font
					(size 1.27 1.27)
				)
				(justify mirror)
			)
		)
		(property "Value" ""
			(at 0 0 90)
			(layer "B.Fab")
			(effects
				(font
					(size 1.27 1.27)
				)
				(justify mirror)
			)
		)
		(duplicate_pad_numbers_are_jumpers no)
		(fp_line
			(start -0.7874 0.4064)
			(end 0.7874 0.4064)
			(stroke
				(width 0.1524)
				(type default)
			)
			(layer "B.SilkS")
		)
		(fp_line
			(start 0.7874 0.4064)
			(end 0.7874 -0.4064)
			(stroke
				(width 0.1524)
				(type default)
			)
			(layer "B.SilkS")
		)
		(fp_line
			(start -0.7874 -0.4064)
			(end -0.7874 0.4064)
			(stroke
				(width 0.1524)
				(type default)
			)
			(layer "B.SilkS")
		)
		(fp_line
			(start 0.7874 -0.4064)
			(end -0.7874 -0.4064)
			(stroke
				(width 0.1524)
				(type default)
			)
			(layer "B.SilkS")
		)
		(fp_line
			(start -0.67945 0.3048)
			(end -0.120396 0.3048)
			(stroke
				(width 0.1)
				(type default)
			)
			(layer "B.Fab")
		)
		(fp_line
			(start -0.120396 0.3048)
			(end -0.120396 0.2794)
			(stroke
				(width 0.1)
				(type default)
			)
			(layer "B.Fab")
		)
		(fp_line
			(start 0.12065 0.3048)
			(end 0.67945 0.3048)
			(stroke
				(width 0.1)
				(type default)
			)
			(layer "B.Fab")
		)
		(fp_line
			(start 0.67945 0.3048)
			(end 0.67945 -0.305054)
			(stroke
				(width 0.1)
				(type default)
			)
			(layer "B.Fab")
		)
		(fp_line
			(start -0.120396 0.2794)
			(end 0.12065 0.2794)
			(stroke
				(width 0.1)
				(type default)
			)
			(layer "B.Fab")
		)
		(fp_line
			(start 0.12065 0.2794)
			(end 0.12065 0.3048)
			(stroke
				(width 0.1)
				(type default)
			)
			(layer "B.Fab")
		)
		(fp_line
			(start -0.12065 -0.2794)
			(end -0.12065 -0.3048)
			(stroke
				(width 0.1)
				(type default)
			)
			(layer "B.Fab")
		)
		(fp_line
			(start 0.12065 -0.2794)
			(end -0.12065 -0.2794)
			(stroke
				(width 0.1)
				(type default)
			)
			(layer "B.Fab")
		)
		(fp_line
			(start -0.67945 -0.3048)
			(end -0.67945 0.3048)
			(stroke
				(width 0.1)
				(type default)
			)
			(layer "B.Fab")
		)
		(fp_line
			(start -0.12065 -0.3048)
			(end -0.67945 -0.3048)
			(stroke
				(width 0.1)
				(type default)
			)
			(layer "B.Fab")
		)
		(fp_line
			(start 0.12065 -0.305054)
			(end 0.12065 -0.2794)
			(stroke
				(width 0.1)
				(type default)
			)
			(layer "B.Fab")
		)
		(fp_line
			(start 0.67945 -0.305054)
			(end 0.12065 -0.305054)
			(stroke
				(width 0.1)
				(type default)
			)
			(layer "B.Fab")
		)
		(pad "1" smd circle
			(at 0.40005 0 90)
			(size 0 0)
			(layers "B.Cu" "B.Mask" "B.Paste")
			(net "V_BMC_LS_DDC_SCL")
		)
		(pad "2" smd circle
			(at -0.40005 0 90)
			(size 0 0)
			(layers "B.Cu" "B.Mask" "B.Paste")
			(net "V_BMC_LS_DDC_SCL_R")
		)
	)
	(footprint ""
		(layer "B.Cu")
		(at 48.00092 -24.11984 -90)
		(property "Reference" "R296"
			(at 0 0 90)
			(layer "B.SilkS")
			(hide yes)
			(effects
				(font
					(size 1.27 1.27)
				)
				(justify mirror)
			)
		)
		(property "Value" ""
			(at 0 0 90)
			(layer "B.Fab")
			(effects
				(font
					(size 1.27 1.27)
				)
				(justify mirror)
			)
		)
		(duplicate_pad_numbers_are_jumpers no)
		(fp_line
			(start -0.7874 0.4064)
			(end 0.7874 0.4064)
			(stroke
				(width 0.1524)
				(type default)
			)
			(layer "B.SilkS")
		)
		(fp_line
			(start 0.7874 0.4064)
			(end 0.7874 -0.4064)
			(stroke
				(width 0.1524)
				(type default)
			)
			(layer "B.SilkS")
		)
		(fp_line
			(start -0.7874 -0.4064)
			(end -0.7874 0.4064)
			(stroke
				(width 0.1524)
				(type default)
			)
			(layer "B.SilkS")
		)
		(fp_line
			(start 0.7874 -0.4064)
			(end -0.7874 -0.4064)
			(stroke
				(width 0.1524)
				(type default)
			)
			(layer "B.SilkS")
		)
		(fp_line
			(start -0.67945 0.3048)
			(end -0.120396 0.3048)
			(stroke
				(width 0.1)
				(type default)
			)
			(layer "B.Fab")
		)
		(fp_line
			(start -0.120396 0.3048)
			(end -0.120396 0.2794)
			(stroke
				(width 0.1)
				(type default)
			)
			(layer "B.Fab")
		)
		(fp_line
			(start 0.12065 0.3048)
			(end 0.67945 0.3048)
			(stroke
				(width 0.1)
				(type default)
			)
			(layer "B.Fab")
		)
		(fp_line
			(start 0.67945 0.3048)
			(end 0.67945 -0.305054)
			(stroke
				(width 0.1)
				(type default)
			)
			(layer "B.Fab")
		)
		(fp_line
			(start -0.120396 0.2794)
			(end 0.12065 0.2794)
			(stroke
				(width 0.1)
				(type default)
			)
			(layer "B.Fab")
		)
		(fp_line
			(start 0.12065 0.2794)
			(end 0.12065 0.3048)
			(stroke
				(width 0.1)
				(type default)
			)
			(layer "B.Fab")
		)
		(fp_line
			(start -0.12065 -0.2794)
			(end -0.12065 -0.3048)
			(stroke
				(width 0.1)
				(type default)
			)
			(layer "B.Fab")
		)
		(fp_line
			(start 0.12065 -0.2794)
			(end -0.12065 -0.2794)
			(stroke
				(width 0.1)
				(type default)
			)
			(layer "B.Fab")
		)
		(fp_line
			(start -0.67945 -0.3048)
			(end -0.67945 0.3048)
			(stroke
				(width 0.1)
				(type default)
			)
			(layer "B.Fab")
		)
		(fp_line
			(start -0.12065 -0.3048)
			(end -0.67945 -0.3048)
			(stroke
				(width 0.1)
				(type default)
			)
			(layer "B.Fab")
		)
		(fp_line
			(start 0.12065 -0.305054)
			(end 0.12065 -0.2794)
			(stroke
				(width 0.1)
				(type default)
			)
			(layer "B.Fab")
		)
		(fp_line
			(start 0.67945 -0.305054)
			(end 0.12065 -0.305054)
			(stroke
				(width 0.1)
				(type default)
			)
			(layer "B.Fab")
		)
		(pad "1" smd circle
			(at 0.40005 0 90)
			(size 0 0)
			(layers "B.Cu" "B.Mask" "B.Paste")
			(net "DEBUG_PORT_PRSNT_BUF_R_EN")
		)
		(pad "2" smd circle
			(at -0.40005 0 90)
			(size 0 0)
			(layers "B.Cu" "B.Mask" "B.Paste")
			(net "GND")
		)
	)
	(footprint ""
		(layer "B.Cu")
		(at 46.577758 -60.564776 180)
		(property "Reference" "C138"
			(at 0 0 0)
			(layer "B.SilkS")
			(hide yes)
			(effects
				(font
					(size 1.27 1.27)
				)
				(justify mirror)
			)
		)
		(property "Value" ""
			(at 0 0 0)
			(layer "B.Fab")
			(effects
				(font
					(size 1.27 1.27)
				)
				(justify mirror)
			)
		)
		(duplicate_pad_numbers_are_jumpers no)
		(fp_line
			(start 0.7874 0.4064)
			(end 0.7874 -0.4064)
			(stroke
				(width 0.1524)
				(type default)
			)
			(layer "B.SilkS")
		)
		(fp_line
			(start 0.7874 -0.4064)
			(end -0.7874 -0.4064)
			(stroke
				(width 0.1524)
				(type default)
			)
			(layer "B.SilkS")
		)
		(fp_line
			(start -0.7874 0.4064)
			(end 0.7874 0.4064)
			(stroke
				(width 0.1524)
				(type default)
			)
			(layer "B.SilkS")
		)
		(fp_line
			(start -0.7874 -0.4064)
			(end -0.7874 0.4064)
			(stroke
				(width 0.1524)
				(type default)
			)
			(layer "B.SilkS")
		)
		(fp_line
			(start 0.67945 0.3048)
			(end 0.67945 -0.305054)
			(stroke
				(width 0.1)
				(type default)
			)
			(layer "B.Fab")
		)
		(fp_line
			(start 0.67945 -0.305054)
			(end 0.12065 -0.305054)
			(stroke
				(width 0.1)
				(type default)
			)
			(layer "B.Fab")
		)
		(fp_line
			(start 0.12065 0.3048)
			(end 0.67945 0.3048)
			(stroke
				(width 0.1)
				(type default)
			)
			(layer "B.Fab")
		)
		(fp_line
			(start 0.12065 0.2794)
			(end 0.12065 0.3048)
			(stroke
				(width 0.1)
				(type default)
			)
			(layer "B.Fab")
		)
		(fp_line
			(start 0.12065 -0.2794)
			(end -0.12065 -0.2794)
			(stroke
				(width 0.1)
				(type default)
			)
			(layer "B.Fab")
		)
		(fp_line
			(start 0.12065 -0.305054)
			(end 0.12065 -0.2794)
			(stroke
				(width 0.1)
				(type default)
			)
			(layer "B.Fab")
		)
		(fp_line
			(start -0.120396 0.3048)
			(end -0.120396 0.2794)
			(stroke
				(width 0.1)
				(type default)
			)
			(layer "B.Fab")
		)
		(fp_line
			(start -0.120396 0.2794)
			(end 0.12065 0.2794)
			(stroke
				(width 0.1)
				(type default)
			)
			(layer "B.Fab")
		)
		(fp_line
			(start -0.12065 -0.2794)
			(end -0.12065 -0.3048)
			(stroke
				(width 0.1)
				(type default)
			)
			(layer "B.Fab")
		)
		(fp_line
			(start -0.12065 -0.3048)
			(end -0.67945 -0.3048)
			(stroke
				(width 0.1)
				(type default)
			)
			(layer "B.Fab")
		)
		(fp_line
			(start -0.67945 0.3048)
			(end -0.120396 0.3048)
			(stroke
				(width 0.1)
				(type default)
			)
			(layer "B.Fab")
		)
		(fp_line
			(start -0.67945 -0.3048)
			(end -0.67945 0.3048)
			(stroke
				(width 0.1)
				(type default)
			)
			(layer "B.Fab")
		)
		(pad "1" smd circle
			(at 0.40005 0)
			(size 0 0)
			(layers "B.Cu" "B.Mask" "B.Paste")
			(net "A_BMC_ADCVREFN0")
		)
		(pad "2" smd circle
			(at -0.40005 0)
			(size 0 0)
			(layers "B.Cu" "B.Mask" "B.Paste")
			(net "A_BMC_ADCVREFP0")
		)
	)
	(footprint ""
		(layer "B.Cu")
		(at 54.3814 -65.3288 90)
		(property "Reference" "R452"
			(at 0 0 90)
			(layer "B.SilkS")
			(hide yes)
			(effects
				(font
					(size 1.27 1.27)
				)
				(justify mirror)
			)
		)
		(property "Value" ""
			(at 0 0 90)
			(layer "B.Fab")
			(effects
				(font
					(size 1.27 1.27)
				)
				(justify mirror)
			)
		)
		(duplicate_pad_numbers_are_jumpers no)
		(fp_line
			(start 0.7874 -0.4064)
			(end -0.7874 -0.4064)
			(stroke
				(width 0.1524)
				(type default)
			)
			(layer "B.SilkS")
		)
		(fp_line
			(start -0.7874 -0.4064)
			(end -0.7874 0.4064)
			(stroke
				(width 0.1524)
				(type default)
			)
			(layer "B.SilkS")
		)
		(fp_line
			(start 0.7874 0.4064)
			(end 0.7874 -0.4064)
			(stroke
				(width 0.1524)
				(type default)
			)
			(layer "B.SilkS")
		)
		(fp_line
			(start -0.7874 0.4064)
			(end 0.7874 0.4064)
			(stroke
				(width 0.1524)
				(type default)
			)
			(layer "B.SilkS")
		)
		(fp_line
			(start 0.67945 -0.305054)
			(end 0.12065 -0.305054)
			(stroke
				(width 0.1)
				(type default)
			)
			(layer "B.Fab")
		)
		(fp_line
			(start 0.12065 -0.305054)
			(end 0.12065 -0.2794)
			(stroke
				(width 0.1)
				(type default)
			)
			(layer "B.Fab")
		)
		(fp_line
			(start -0.12065 -0.3048)
			(end -0.67945 -0.3048)
			(stroke
				(width 0.1)
				(type default)
			)
			(layer "B.Fab")
		)
		(fp_line
			(start -0.67945 -0.3048)
			(end -0.67945 0.3048)
			(stroke
				(width 0.1)
				(type default)
			)
			(layer "B.Fab")
		)
		(fp_line
			(start 0.12065 -0.2794)
			(end -0.12065 -0.2794)
			(stroke
				(width 0.1)
				(type default)
			)
			(layer "B.Fab")
		)
		(fp_line
			(start -0.12065 -0.2794)
			(end -0.12065 -0.3048)
			(stroke
				(width 0.1)
				(type default)
			)
			(layer "B.Fab")
		)
		(fp_line
			(start 0.12065 0.2794)
			(end 0.12065 0.3048)
			(stroke
				(width 0.1)
				(type default)
			)
			(layer "B.Fab")
		)
		(fp_line
			(start -0.120396 0.2794)
			(end 0.12065 0.2794)
			(stroke
				(width 0.1)
				(type default)
			)
			(layer "B.Fab")
		)
		(fp_line
			(start 0.67945 0.3048)
			(end 0.67945 -0.305054)
			(stroke
				(width 0.1)
				(type default)
			)
			(layer "B.Fab")
		)
		(fp_line
			(start 0.12065 0.3048)
			(end 0.67945 0.3048)
			(stroke
				(width 0.1)
				(type default)
			)
			(layer "B.Fab")
		)
		(fp_line
			(start -0.120396 0.3048)
			(end -0.120396 0.2794)
			(stroke
				(width 0.1)
				(type default)
			)
			(layer "B.Fab")
		)
		(fp_line
			(start -0.67945 0.3048)
			(end -0.120396 0.3048)
			(stroke
				(width 0.1)
				(type default)
			)
			(layer "B.Fab")
		)
		(pad "1" smd circle
			(at 0.40005 0 270)
			(size 0 0)
			(layers "B.Cu" "B.Mask" "B.Paste")
			(net "P3V3_AUX")
		)
		(pad "2" smd circle
			(at -0.40005 0 270)
			(size 0 0)
			(layers "B.Cu" "B.Mask" "B.Paste")
			(net "RST_WDTRST_PLD_N")
		)
	)
	(footprint ""
		(layer "B.Cu")
		(at 68.58254 -29.810964)
		(property "Reference" "R15"
			(at 0 0 0)
			(layer "B.SilkS")
			(hide yes)
			(effects
				(font
					(size 1.27 1.27)
				)
				(justify mirror)
			)
		)
		(property "Value" ""
			(at 0 0 0)
			(layer "B.Fab")
			(effects
				(font
					(size 1.27 1.27)
				)
				(justify mirror)
			)
		)
		(duplicate_pad_numbers_are_jumpers no)
		(fp_line
			(start -0.7874 -0.4064)
			(end -0.7874 0.4064)
			(stroke
				(width 0.1524)
				(type default)
			)
			(layer "B.SilkS")
		)
		(fp_line
			(start -0.7874 0.4064)
			(end 0.7874 0.4064)
			(stroke
				(width 0.1524)
				(type default)
			)
			(layer "B.SilkS")
		)
		(fp_line
			(start 0.7874 -0.4064)
			(end -0.7874 -0.4064)
			(stroke
				(width 0.1524)
				(type default)
			)
			(layer "B.SilkS")
		)
		(fp_line
			(start 0.7874 0.4064)
			(end 0.7874 -0.4064)
			(stroke
				(width 0.1524)
				(type default)
			)
			(layer "B.SilkS")
		)
		(fp_line
			(start -0.67945 -0.3048)
			(end -0.67945 0.3048)
			(stroke
				(width 0.1)
				(type default)
			)
			(layer "B.Fab")
		)
		(fp_line
			(start -0.67945 0.3048)
			(end -0.120396 0.3048)
			(stroke
				(width 0.1)
				(type default)
			)
			(layer "B.Fab")
		)
		(fp_line
			(start -0.12065 -0.3048)
			(end -0.67945 -0.3048)
			(stroke
				(width 0.1)
				(type default)
			)
			(layer "B.Fab")
		)
		(fp_line
			(start -0.12065 -0.2794)
			(end -0.12065 -0.3048)
			(stroke
				(width 0.1)
				(type default)
			)
			(layer "B.Fab")
		)
		(fp_line
			(start -0.120396 0.2794)
			(end 0.12065 0.2794)
			(stroke
				(width 0.1)
				(type default)
			)
			(layer "B.Fab")
		)
		(fp_line
			(start -0.120396 0.3048)
			(end -0.120396 0.2794)
			(stroke
				(width 0.1)
				(type default)
			)
			(layer "B.Fab")
		)
		(fp_line
			(start 0.12065 -0.305054)
			(end 0.12065 -0.2794)
			(stroke
				(width 0.1)
				(type default)
			)
			(layer "B.Fab")
		)
		(fp_line
			(start 0.12065 -0.2794)
			(end -0.12065 -0.2794)
			(stroke
				(width 0.1)
				(type default)
			)
			(layer "B.Fab")
		)
		(fp_line
			(start 0.12065 0.2794)
			(end 0.12065 0.3048)
			(stroke
				(width 0.1)
				(type default)
			)
			(layer "B.Fab")
		)
		(fp_line
			(start 0.12065 0.3048)
			(end 0.67945 0.3048)
			(stroke
				(width 0.1)
				(type default)
			)
			(layer "B.Fab")
		)
		(fp_line
			(start 0.67945 -0.305054)
			(end 0.12065 -0.305054)
			(stroke
				(width 0.1)
				(type default)
			)
			(layer "B.Fab")
		)
		(fp_line
			(start 0.67945 0.3048)
			(end 0.67945 -0.305054)
			(stroke
				(width 0.1)
				(type default)
			)
			(layer "B.Fab")
		)
		(pad "1" smd circle
			(at 0.40005 0 180)
			(size 0 0)
			(layers "B.Cu" "B.Mask" "B.Paste")
			(net "PD_FRU_WC_N")
		)
		(pad "2" smd circle
			(at -0.40005 0 180)
			(size 0 0)
			(layers "B.Cu" "B.Mask" "B.Paste")
			(net "GND")
		)
	)
)
